(kicad_pcb
	(version 20260206)
	(generator "pcbnew")
	(generator_version "10.0")
	(general
		(thickness 1.6)
		(legacy_teardrops no)
	)
	(paper "A4")
	(title_block
		(title "peb — Lightning_PEB_BRD.brd")
		(comment 1 "Lightning (Wiwynn / Facebook NVMe JBOF) / footprints 543-548 of 2563")
	)
	(layers
		(0 "F.Cu" signal "TOP")
		(4 "In1.Cu" signal "L2GND")
		(6 "In2.Cu" signal "L3")
		(8 "In3.Cu" signal "L4VCC")
		(10 "In4.Cu" signal "L5VCC")
		(12 "In5.Cu" signal "L6")
		(14 "In6.Cu" signal "L7GND")
		(2 "B.Cu" signal "BOTTOM")
		(9 "F.Adhes" user "F.Adhesive")
		(11 "B.Adhes" user "B.Adhesive")
		(13 "F.Paste" user "Package Geometry/Pastemask Top")
		(15 "B.Paste" user "Package Geometry/Pastemask Bottom")
		(5 "F.SilkS" user "Ref Des/Silkscreen Top")
		(7 "B.SilkS" user "Ref Des/Silkscreen Bottom")
		(1 "F.Mask" user "Board Geometry/Soldermask Top")
		(3 "B.Mask" user "Board Geometry/Soldermask Bottom")
		(17 "Dwgs.User" user "User.Drawings")
		(19 "Cmts.User" user "User.Comments")
		(21 "Eco1.User" user "User.Eco1")
		(23 "Eco2.User" user "User.Eco2")
		(25 "Edge.Cuts" user "Board Geometry/Outline")
		(27 "Margin" user)
		(31 "F.CrtYd" user "Package Geometry/Place Bound Top")
		(29 "B.CrtYd" user "Package Geometry/Place Bound Bottom")
		(35 "F.Fab" user "Ref Des/Assembly Top")
		(33 "B.Fab" user "Ref Des/Assembly Bottom")
	)
	(footprint ""
		(layer "F.Cu")
		(at 101.192076 -212.420454 180)
		(property "Reference" "C154"
			(at 0 0 180)
			(layer "F.SilkS")
			(hide yes)
			(effects
				(font
					(size 1.27 1.27)
				)
			)
		)
		(property "Value" "SCD22U10V2KX-1GP"
			(at 1.1811 -2.7051 180)
			(unlocked yes)
			(layer "F.Fab")
			(hide yes)
			(effects
				(font
					(size 1.016 1.016)
					(thickness 0.1524)
				)
			)
		)
		(property "Device Type" "C402H22"
			(at 1.1811 -4.2291 180)
			(unlocked yes)
			(layer "F.Fab")
			(hide yes)
			(effects
				(font
					(size 1.016 1.016)
					(thickness 0.1524)
				)
			)
		)
		(duplicate_pad_numbers_are_jumpers no)
		(fp_rect
			(start -0.4318 0.9525)
			(end 0.4318 -0.9525)
			(stroke
				(width 0)
				(type default)
			)
			(fill no)
			(layer "F.CrtYd")
		)
		(fp_rect
			(start -0.4318 0.9525)
			(end 0.4318 -0.9525)
			(stroke
				(width 0)
				(type default)
			)
			(fill no)
			(layer "F.Fab")
		)
		(pad "1" smd custom
			(at 0 -0.4445 180)
			(size 0.1524 0.1524)
			(layers "F.Cu" "F.Mask" "F.Paste")
			(net "PCIE_TX_CAP_P62")
			(options
				(clearance outline)
				(anchor circle)
			)
			(primitives
				(gr_poly
					(pts
						(arc
							(start 0.3048 -0.2032)
							(mid 0.275042 -0.275042)
							(end 0.2032 -0.3048)
						)
						(arc
							(start -0.2032 -0.3048)
							(mid -0.275042 -0.275042)
							(end -0.3048 -0.2032)
						)
						(arc
							(start -0.3048 0.2032)
							(mid -0.275042 0.275042)
							(end -0.2032 0.3048)
						)
						(arc
							(start 0.2032 0.3048)
							(mid 0.275042 0.275042)
							(end 0.3048 0.2032)
						)
					)
					(width 0)
					(fill yes)
				)
			)
		)
		(pad "2" smd custom
			(at 0 0.4445 180)
			(size 0.1524 0.1524)
			(layers "F.Cu" "F.Mask" "F.Paste")
			(net "PCIE_TX_P62")
			(options
				(clearance outline)
				(anchor circle)
			)
			(primitives
				(gr_poly
					(pts
						(arc
							(start 0.3048 -0.2032)
							(mid 0.275042 -0.275042)
							(end 0.2032 -0.3048)
						)
						(arc
							(start -0.2032 -0.3048)
							(mid -0.275042 -0.275042)
							(end -0.3048 -0.2032)
						)
						(arc
							(start -0.3048 0.2032)
							(mid -0.275042 0.275042)
							(end -0.2032 0.3048)
						)
						(arc
							(start 0.2032 0.3048)
							(mid 0.275042 0.275042)
							(end 0.3048 0.2032)
						)
					)
					(width 0)
					(fill yes)
				)
			)
		)
	)
	(footprint ""
		(layer "F.Cu")
		(at 126.627128 -33.159192 -90)
		(property "Reference" "R667"
			(at 0 0 270)
			(layer "F.SilkS")
			(hide yes)
			(effects
				(font
					(size 1.27 1.27)
				)
			)
		)
		(property "Value" "0R2J-2-GP"
			(at 0.064008 -3.993896 270)
			(unlocked yes)
			(layer "F.Fab")
			(hide yes)
			(effects
				(font
					(size 1.016 1.016)
					(thickness 0.1524)
				)
			)
		)
		(property "Device Type" "R402H16"
			(at 0.064008 -5.517896 270)
			(unlocked yes)
			(layer "F.Fab")
			(hide yes)
			(effects
				(font
					(size 1.016 1.016)
					(thickness 0.1524)
				)
			)
		)
		(duplicate_pad_numbers_are_jumpers no)
		(fp_line
			(start -0.508 -0.9398)
			(end -0.508 0.9398)
			(stroke
				(width 0.1524)
				(type default)
			)
			(layer "F.SilkS")
		)
		(fp_line
			(start 0.508 -0.9398)
			(end -0.508 -0.9398)
			(stroke
				(width 0.1524)
				(type default)
			)
			(layer "F.SilkS")
		)
		(fp_rect
			(start -0.508 0.9398)
			(end 0.508 -0.9398)
			(stroke
				(width 0)
				(type default)
			)
			(fill no)
			(layer "F.CrtYd")
		)
		(fp_rect
			(start -0.508 0.9398)
			(end 0.508 -0.9398)
			(stroke
				(width 0)
				(type default)
			)
			(fill no)
			(layer "F.Fab")
		)
		(pad "1" smd custom
			(at 0 -0.4445 270)
			(size 0.1397 0.1397)
			(layers "F.Cu" "F.Mask" "F.Paste")
			(net "8644_USB_DN1")
			(options
				(clearance outline)
				(anchor circle)
			)
			(primitives
				(gr_poly
					(pts
						(arc
							(start -0.1778 -0.2794)
							(mid -0.249642 -0.249642)
							(end -0.2794 -0.1778)
						)
						(arc
							(start -0.2794 0.1778)
							(mid -0.249642 0.249642)
							(end -0.1778 0.2794)
						)
						(arc
							(start 0.1778 0.2794)
							(mid 0.249642 0.249642)
							(end 0.2794 0.1778)
						)
						(arc
							(start 0.2794 -0.1778)
							(mid 0.249642 -0.249642)
							(end 0.1778 -0.2794)
						)
					)
					(width 0)
					(fill yes)
				)
			)
		)
		(pad "2" smd custom
			(at 0 0.4445 270)
			(size 0.1397 0.1397)
			(layers "F.Cu" "F.Mask" "F.Paste")
			(net "P3V3_STBY")
			(options
				(clearance outline)
				(anchor circle)
			)
			(primitives
				(gr_poly
					(pts
						(arc
							(start -0.1778 -0.2794)
							(mid -0.249642 -0.249642)
							(end -0.2794 -0.1778)
						)
						(arc
							(start -0.2794 0.1778)
							(mid -0.249642 0.249642)
							(end -0.1778 0.2794)
						)
						(arc
							(start 0.1778 0.2794)
							(mid 0.249642 0.249642)
							(end 0.2794 0.1778)
						)
						(arc
							(start 0.2794 -0.1778)
							(mid 0.249642 -0.249642)
							(end 0.1778 -0.2794)
						)
					)
					(width 0)
					(fill yes)
				)
			)
		)
	)
	(footprint ""
		(layer "F.Cu")
		(at 151.730202 -65.432432 90)
		(property "Reference" "PC191"
			(at 0 0 90)
			(layer "F.SilkS")
			(hide yes)
			(effects
				(font
					(size 1.27 1.27)
				)
			)
		)
		(property "Value" "SCD1U50V3KX-GP"
			(at 0 -2.8194 90)
			(unlocked yes)
			(layer "F.Fab")
			(hide yes)
			(effects
				(font
					(size 1.016 1.016)
					(thickness 0.1524)
				)
			)
		)
		(property "Device Type" "C603H36"
			(at 0 -4.3434 90)
			(unlocked yes)
			(layer "F.Fab")
			(hide yes)
			(effects
				(font
					(size 1.016 1.016)
					(thickness 0.1524)
				)
			)
		)
		(duplicate_pad_numbers_are_jumpers no)
		(fp_line
			(start 0.508 0)
			(end -0.508 0)
			(stroke
				(width 0.2032)
				(type default)
			)
			(layer "F.SilkS")
		)
		(fp_rect
			(start -0.5842 1.3335)
			(end 0.5842 -1.3335)
			(stroke
				(width 0)
				(type default)
			)
			(fill no)
			(layer "F.CrtYd")
		)
		(fp_rect
			(start -0.5842 1.3335)
			(end 0.5842 -1.3335)
			(stroke
				(width 0)
				(type default)
			)
			(fill no)
			(layer "F.Fab")
		)
		(pad "1" smd custom
			(at 0 -0.762 90)
			(size 0.2159 0.2159)
			(layers "F.Cu" "F.Mask" "F.Paste")
			(net "P0V9_VIN")
			(options
				(clearance outline)
				(anchor circle)
			)
			(primitives
				(gr_poly
					(pts
						(arc
							(start -0.3302 -0.4318)
							(mid -0.402042 -0.402042)
							(end -0.4318 -0.3302)
						)
						(arc
							(start -0.4318 0.3302)
							(mid -0.402042 0.402042)
							(end -0.3302 0.4318)
						)
						(arc
							(start 0.3302 0.4318)
							(mid 0.402042 0.402042)
							(end 0.4318 0.3302)
						)
						(arc
							(start 0.4318 -0.3302)
							(mid 0.402042 -0.402042)
							(end 0.3302 -0.4318)
						)
					)
					(width 0)
					(fill yes)
				)
			)
		)
		(pad "2" smd custom
			(at 0 0.762 90)
			(size 0.2159 0.2159)
			(layers "F.Cu" "F.Mask" "F.Paste")
			(net "GND")
			(options
				(clearance outline)
				(anchor circle)
			)
			(primitives
				(gr_poly
					(pts
						(arc
							(start -0.3302 -0.4318)
							(mid -0.402042 -0.402042)
							(end -0.4318 -0.3302)
						)
						(arc
							(start -0.4318 0.3302)
							(mid -0.402042 0.402042)
							(end -0.3302 0.4318)
						)
						(arc
							(start 0.3302 0.4318)
							(mid 0.402042 0.402042)
							(end 0.4318 0.3302)
						)
						(arc
							(start 0.4318 -0.3302)
							(mid 0.402042 -0.402042)
							(end 0.3302 -0.4318)
						)
					)
					(width 0)
					(fill yes)
				)
			)
		)
	)
	(footprint ""
		(layer "F.Cu")
		(at 117.3226 -17.0688 180)
		(property "Reference" "R753"
			(at 0 0 180)
			(layer "F.SilkS")
			(hide yes)
			(effects
				(font
					(size 1.27 1.27)
				)
			)
		)
		(property "Value" "4K7R2F-GP"
			(at 0.064008 -3.993896 180)
			(unlocked yes)
			(layer "F.Fab")
			(hide yes)
			(effects
				(font
					(size 1.016 1.016)
					(thickness 0.1524)
				)
			)
		)
		(property "Device Type" "R402H16"
			(at 0.064008 -5.517896 180)
			(unlocked yes)
			(layer "F.Fab")
			(hide yes)
			(effects
				(font
					(size 1.016 1.016)
					(thickness 0.1524)
				)
			)
		)
		(duplicate_pad_numbers_are_jumpers no)
		(fp_line
			(start 0.508 -0.9398)
			(end -0.508 -0.9398)
			(stroke
				(width 0.1524)
				(type default)
			)
			(layer "F.SilkS")
		)
		(fp_line
			(start -0.508 -0.9398)
			(end -0.508 0.9398)
			(stroke
				(width 0.1524)
				(type default)
			)
			(layer "F.SilkS")
		)
		(fp_rect
			(start -0.508 0.9398)
			(end 0.508 -0.9398)
			(stroke
				(width 0)
				(type default)
			)
			(fill no)
			(layer "F.CrtYd")
		)
		(fp_rect
			(start -0.508 0.9398)
			(end 0.508 -0.9398)
			(stroke
				(width 0)
				(type default)
			)
			(fill no)
			(layer "F.Fab")
		)
		(pad "1" smd custom
			(at 0 -0.4445 180)
			(size 0.1397 0.1397)
			(layers "F.Cu" "F.Mask" "F.Paste")
			(net "GND")
			(options
				(clearance outline)
				(anchor circle)
			)
			(primitives
				(gr_poly
					(pts
						(arc
							(start -0.1778 -0.2794)
							(mid -0.249642 -0.249642)
							(end -0.2794 -0.1778)
						)
						(arc
							(start -0.2794 0.1778)
							(mid -0.249642 0.249642)
							(end -0.1778 0.2794)
						)
						(arc
							(start 0.1778 0.2794)
							(mid 0.249642 0.249642)
							(end 0.2794 0.1778)
						)
						(arc
							(start 0.2794 -0.1778)
							(mid 0.249642 -0.249642)
							(end 0.1778 -0.2794)
						)
					)
					(width 0)
					(fill yes)
				)
			)
		)
		(pad "2" smd custom
			(at 0 0.4445 180)
			(size 0.1397 0.1397)
			(layers "F.Cu" "F.Mask" "F.Paste")
			(net "U54_A0")
			(options
				(clearance outline)
				(anchor circle)
			)
			(primitives
				(gr_poly
					(pts
						(arc
							(start -0.1778 -0.2794)
							(mid -0.249642 -0.249642)
							(end -0.2794 -0.1778)
						)
						(arc
							(start -0.2794 0.1778)
							(mid -0.249642 0.249642)
							(end -0.1778 0.2794)
						)
						(arc
							(start 0.1778 0.2794)
							(mid 0.249642 0.249642)
							(end 0.2794 0.1778)
						)
						(arc
							(start 0.2794 -0.1778)
							(mid 0.249642 -0.249642)
							(end 0.1778 -0.2794)
						)
					)
					(width 0)
					(fill yes)
				)
			)
		)
	)
	(footprint ""
		(layer "F.Cu")
		(at 122.377454 -83.58759 90)
		(property "Reference" "TP800"
			(at 0 0 90)
			(layer "F.SilkS")
			(hide yes)
			(effects
				(font
					(size 1.27 1.27)
				)
			)
		)
		(property "Value" "TPAD28-2-GP"
			(at -0.0127 -1.6637 90)
			(unlocked yes)
			(layer "F.Fab")
			(hide yes)
			(effects
				(font
					(size 1.016 1.016)
					(thickness 0.1524)
				)
			)
		)
		(property "Device Type" "TPAD28"
			(at -0.0127 -3.1877 90)
			(unlocked yes)
			(layer "F.Fab")
			(hide yes)
			(effects
				(font
					(size 1.016 1.016)
					(thickness 0.1524)
				)
			)
		)
		(duplicate_pad_numbers_are_jumpers no)
		(fp_poly
			(pts
				(arc
					(start 0 0.3556)
					(mid 0 -0.3556)
					(end 0 0.3556)
				)
			)
			(stroke
				(width 0)
				(type default)
			)
			(fill no)
			(layer "F.CrtYd")
		)
		(fp_poly
			(pts
				(arc
					(start 0 0.6096)
					(mid 0 -0.6096)
					(end 0 0.6096)
				)
			)
			(stroke
				(width 0)
				(type default)
			)
			(fill no)
			(layer "F.Fab")
		)
		(pad "1" smd circle
			(at 0 0 90)
			(size 0.7112 0.7112)
			(layers "F.Cu" "F.Mask" "F.Paste")
			(net "RTC_CLK_OUT")
		)
	)
	(footprint ""
		(layer "F.Cu")
		(at 70.993 -30.988 90)
		(property "Reference" "C267"
			(at 0 0 90)
			(layer "F.SilkS")
			(hide yes)
			(effects
				(font
					(size 1.27 1.27)
				)
			)
		)
		(property "Value" "SC100P50V2JN-3GP"
			(at 1.1811 -2.7051 90)
			(unlocked yes)
			(layer "F.Fab")
			(hide yes)
			(effects
				(font
					(size 1.016 1.016)
					(thickness 0.1524)
				)
			)
		)
		(property "Device Type" "C402H22"
			(at 1.1811 -4.2291 90)
			(unlocked yes)
			(layer "F.Fab")
			(hide yes)
			(effects
				(font
					(size 1.016 1.016)
					(thickness 0.1524)
				)
			)
		)
		(duplicate_pad_numbers_are_jumpers no)
		(fp_rect
			(start -0.4318 0.9525)
			(end 0.4318 -0.9525)
			(stroke
				(width 0)
				(type default)
			)
			(fill no)
			(layer "F.CrtYd")
		)
		(fp_rect
			(start -0.4318 0.9525)
			(end 0.4318 -0.9525)
			(stroke
				(width 0)
				(type default)
			)
			(fill no)
			(layer "F.Fab")
		)
		(pad "1" smd custom
			(at 0 -0.4445 90)
			(size 0.1524 0.1524)
			(layers "F.Cu" "F.Mask" "F.Paste")
			(net "P3V3_STBY_VFB")
			(options
				(clearance outline)
				(anchor circle)
			)
			(primitives
				(gr_poly
					(pts
						(arc
							(start 0.3048 -0.2032)
							(mid 0.275042 -0.275042)
							(end 0.2032 -0.3048)
						)
						(arc
							(start -0.2032 -0.3048)
							(mid -0.275042 -0.275042)
							(end -0.3048 -0.2032)
						)
						(arc
							(start -0.3048 0.2032)
							(mid -0.275042 0.275042)
							(end -0.2032 0.3048)
						)
						(arc
							(start 0.2032 0.3048)
							(mid 0.275042 0.275042)
							(end 0.3048 0.2032)
						)
					)
					(width 0)
					(fill yes)
				)
			)
		)
		(pad "2" smd custom
			(at 0 0.4445 90)
			(size 0.1524 0.1524)
			(layers "F.Cu" "F.Mask" "F.Paste")
			(net "P3V3_STBY_VFB_R")
			(options
				(clearance outline)
				(anchor circle)
			)
			(primitives
				(gr_poly
					(pts
						(arc
							(start 0.3048 -0.2032)
							(mid 0.275042 -0.275042)
							(end 0.2032 -0.3048)
						)
						(arc
							(start -0.2032 -0.3048)
							(mid -0.275042 -0.275042)
							(end -0.3048 -0.2032)
						)
						(arc
							(start -0.3048 0.2032)
							(mid -0.275042 0.275042)
							(end -0.2032 0.3048)
						)
						(arc
							(start 0.2032 0.3048)
							(mid 0.275042 0.275042)
							(end 0.3048 0.2032)
						)
					)
					(width 0)
					(fill yes)
				)
			)
		)
	)
)
